(kicad_pcb
	(version 20260206)
	(generator "pcbnew")
	(generator_version "10.0")
	(general
		(thickness 1.6)
		(legacy_teardrops no)
	)
	(paper "A4")
	(title_block
		(title "04192023_DAF0TMB3IC0_F0TG_MB_C_brd_V02_OCP.brd")
		(comment 1 "Grand Teton / footprint 827 of 8354 (U6017), pads 224-336 of 354")
	)
	(layers
		(0 "F.Cu" signal "TOP")
		(4 "In1.Cu" signal "GND")
		(6 "In2.Cu" signal "IN1")
		(8 "In3.Cu" signal "GND1")
		(10 "In4.Cu" signal "IN2")
		(12 "In5.Cu" signal "GND2")
		(14 "In6.Cu" signal "IN3")
		(16 "In7.Cu" signal "GND3")
		(18 "In8.Cu" signal "VCC")
		(20 "In9.Cu" signal "VCC1")
		(22 "In10.Cu" signal "GND4")
		(24 "In11.Cu" signal "IN4")
		(26 "In12.Cu" signal "GND5")
		(28 "In13.Cu" signal "IN5")
		(30 "In14.Cu" signal "GND6")
		(32 "In15.Cu" signal "IN6")
		(34 "In16.Cu" signal "GND7")
		(2 "B.Cu" signal "BOTTOM")
		(9 "F.Adhes" user "F.Adhesive")
		(11 "B.Adhes" user "B.Adhesive")
		(13 "F.Paste" user "Package Geometry/Pastemask Top")
		(15 "B.Paste" user "Package Geometry/Pastemask Bottom")
		(5 "F.SilkS" user "Ref Des/Silkscreen Top")
		(7 "B.SilkS" user "Ref Des/Silkscreen Bottom")
		(1 "F.Mask" user "Board Geometry/Soldermask Top")
		(3 "B.Mask" user "Board Geometry/Soldermask Bottom")
		(17 "Dwgs.User" user "User.Drawings")
		(19 "Cmts.User" user "User.Comments")
		(21 "Eco1.User" user "User.Eco1")
		(23 "Eco2.User" user "User.Eco2")
		(25 "Edge.Cuts" user "Board Geometry/Outline")
		(27 "Margin" user)
		(31 "F.CrtYd" user "Package Geometry/Place Bound Top")
		(29 "B.CrtYd" user "Package Geometry/Place Bound Bottom")
		(35 "F.Fab" user "Ref Des/Assembly Top")
		(33 "B.Fab" user "Ref Des/Assembly Bottom")
	)
	(footprint ""
		(layer "F.Cu")
		(at 123.567952 -387.342634)
		(property "Reference" "U6017"
			(at -6.180074 -7.979664 0)
			(unlocked yes)
			(layer "F.SilkS")
			(effects
				(font
					(size 0.7874 0.5842)
					(thickness 0.1524)
				)
				(justify left)
			)
		)
		(property "Value" ""
			(at 0 0 0)
			(layer "F.Fab")
			(effects
				(font
					(size 1.27 1.27)
				)
			)
		)
		(duplicate_pad_numbers_are_jumpers no)
		(pad "DY32" smd circle
			(at -5.997448 2.724912)
			(size 0.381 0.381)
			(layers "F.Cu" "F.Mask" "F.Paste")
			(net "GND")
		)
		(pad "E8" smd circle
			(at 10.366502 -1.988312)
			(size 0.3048 0.3048)
			(layers "F.Cu" "F.Mask" "F.Paste")
			(net "JTAG_TRST_RT_CPU1_P3_N")
		)
		(pad "E11" smd circle
			(at 10.366502 -1.388364)
			(size 0.3048 0.3048)
			(layers "F.Cu" "F.Mask" "F.Paste")
			(net "RXDET_BYP_RT_CPU1_P3")
		)
		(pad "E14" smd circle
			(at 10.366502 -0.788416)
			(size 0.3048 0.3048)
			(layers "F.Cu" "F.Mask" "F.Paste")
			(net "GND")
		)
		(pad "E18" smd circle
			(at 10.366502 -0.188468)
			(size 0.3048 0.3048)
			(layers "F.Cu" "F.Mask" "F.Paste")
			(net "Net_2228")
		)
		(pad "E27" smd circle
			(at 10.366502 1.61163)
			(size 0.3048 0.3048)
			(layers "F.Cu" "F.Mask" "F.Paste")
			(net "GND")
		)
		(pad "E30" smd circle
			(at 10.366502 2.211578)
			(size 0.3048 0.3048)
			(layers "F.Cu" "F.Mask" "F.Paste")
			(net "GND")
		)
		(pad "E33" smd circle
			(at 10.366502 2.811526)
			(size 0.3048 0.3048)
			(layers "F.Cu" "F.Mask" "F.Paste")
			(net "GND")
		)
		(pad "EA2" smd circle
			(at -6.050026 -3.41884)
			(size 0.3048 0.3048)
			(layers "F.Cu" "F.Mask" "F.Paste")
			(net "GND")
		)
		(pad "EA34" smd circle
			(at -6.050026 3.420364)
			(size 0.3048 0.3048)
			(layers "F.Cu" "F.Mask" "F.Paste")
			(net "GND")
		)
		(pad "EB1" smd oval
			(at -6.35 -3.938524)
			(size 0.254 0.3302)
			(layers "F.Cu" "F.Mask" "F.Paste")
			(net "GND")
		)
		(pad "EB35" smd oval
			(at -6.35 3.940048)
			(size 0.254 0.3302)
			(layers "F.Cu" "F.Mask" "F.Paste")
			(net "GND")
		)
		(pad "EC7" smd circle
			(at -6.397498 -2.12471)
			(size 0.381 0.381)
			(layers "F.Cu" "F.Mask" "F.Paste")
			(net "P5E_CPU1_P3_TX_BUF_DP<2>")
		)
		(pad "EC26" smd circle
			(at -6.397498 1.339342)
			(size 0.381 0.381)
			(layers "F.Cu" "F.Mask" "F.Paste")
			(net "P5E_CPU1_P3_RX_DP<2>")
		)
		(pad "ED2" smd circle
			(at -6.649974 -3.41884)
			(size 0.3048 0.3048)
			(layers "F.Cu" "F.Mask" "F.Paste")
			(net "P5E_CPU1_P3_RX_BUF_DN<2>")
		)
		(pad "ED34" smd circle
			(at -6.649974 3.420364)
			(size 0.3048 0.3048)
			(layers "F.Cu" "F.Mask" "F.Paste")
			(net "P5E_CPU1_P3_TX_C_DN<2>")
		)
		(pad "EE10" smd circle
			(at -6.797294 -1.431798)
			(size 0.381 0.381)
			(layers "F.Cu" "F.Mask" "F.Paste")
			(net "P5E_CPU1_P3_TX_BUF_DN<2>")
		)
		(pad "EE29" smd circle
			(at -6.797294 2.032254)
			(size 0.381 0.381)
			(layers "F.Cu" "F.Mask" "F.Paste")
			(net "P5E_CPU1_P3_RX_DN<2>")
		)
		(pad "EF1" smd oval
			(at -6.949948 -3.938524)
			(size 0.254 0.3302)
			(layers "F.Cu" "F.Mask" "F.Paste")
			(net "P5E_CPU1_P3_RX_BUF_DP<2>")
		)
		(pad "EF35" smd oval
			(at -6.949948 3.940048)
			(size 0.254 0.3302)
			(layers "F.Cu" "F.Mask" "F.Paste")
			(net "P5E_CPU1_P3_TX_C_DP<2>")
		)
		(pad "EG4" smd circle
			(at -7.197344 -2.817368)
			(size 0.381 0.381)
			(layers "F.Cu" "F.Mask" "F.Paste")
			(net "GND")
		)
		(pad "EG13" smd circle
			(at -7.197344 -0.79629)
			(size 0.3048 0.3048)
			(layers "F.Cu" "F.Mask" "F.Paste")
			(net "GND")
		)
		(pad "EG17" smd circle
			(at -7.197344 -0.296164)
			(size 0.3048 0.3048)
			(layers "F.Cu" "F.Mask" "F.Paste")
			(net "P0V9_CPU1_RT3_2A")
		)
		(pad "EG20" smd circle
			(at -7.197344 0.203708)
			(size 0.3048 0.3048)
			(layers "F.Cu" "F.Mask" "F.Paste")
			(net "P0V9_CPU1_RT3_2A")
		)
		(pad "EG22" smd circle
			(at -7.197344 0.703834)
			(size 0.3048 0.3048)
			(layers "F.Cu" "F.Mask" "F.Paste")
			(net "GND")
		)
		(pad "EG32" smd circle
			(at -7.197344 2.724912)
			(size 0.381 0.381)
			(layers "F.Cu" "F.Mask" "F.Paste")
			(net "GND")
		)
		(pad "EH2" smd circle
			(at -7.249922 -3.41884)
			(size 0.3048 0.3048)
			(layers "F.Cu" "F.Mask" "F.Paste")
			(net "GND")
		)
		(pad "EH34" smd circle
			(at -7.249922 3.420364)
			(size 0.3048 0.3048)
			(layers "F.Cu" "F.Mask" "F.Paste")
			(net "GND")
		)
		(pad "EJ1" smd oval
			(at -7.549896 -3.938524)
			(size 0.254 0.3302)
			(layers "F.Cu" "F.Mask" "F.Paste")
			(net "GND")
		)
		(pad "EJ35" smd oval
			(at -7.549896 3.940048)
			(size 0.254 0.3302)
			(layers "F.Cu" "F.Mask" "F.Paste")
			(net "GND")
		)
		(pad "EK7" smd circle
			(at -7.597394 -2.12471)
			(size 0.381 0.381)
			(layers "F.Cu" "F.Mask" "F.Paste")
			(net "P5E_CPU1_P3_TX_BUF_DP<1>")
		)
		(pad "EK26" smd circle
			(at -7.597394 1.339342)
			(size 0.381 0.381)
			(layers "F.Cu" "F.Mask" "F.Paste")
			(net "P5E_CPU1_P3_RX_DP<1>")
		)
		(pad "EL2" smd circle
			(at -7.850124 -3.41884)
			(size 0.3048 0.3048)
			(layers "F.Cu" "F.Mask" "F.Paste")
			(net "P5E_CPU1_P3_RX_BUF_DN<1>")
		)
		(pad "EL34" smd circle
			(at -7.850124 3.420364)
			(size 0.3048 0.3048)
			(layers "F.Cu" "F.Mask" "F.Paste")
			(net "P5E_CPU1_P3_TX_C_DP<1>")
		)
		(pad "EM10" smd circle
			(at -7.997444 -1.431798)
			(size 0.381 0.381)
			(layers "F.Cu" "F.Mask" "F.Paste")
			(net "P5E_CPU1_P3_TX_BUF_DN<1>")
		)
		(pad "EM29" smd circle
			(at -7.997444 2.032254)
			(size 0.381 0.381)
			(layers "F.Cu" "F.Mask" "F.Paste")
			(net "P5E_CPU1_P3_RX_DN<1>")
		)
		(pad "EN1" smd oval
			(at -8.150098 -3.938524)
			(size 0.254 0.3302)
			(layers "F.Cu" "F.Mask" "F.Paste")
			(net "P5E_CPU1_P3_RX_BUF_DP<1>")
		)
		(pad "EN35" smd oval
			(at -8.150098 3.940048)
			(size 0.254 0.3302)
			(layers "F.Cu" "F.Mask" "F.Paste")
			(net "P5E_CPU1_P3_TX_C_DN<1>")
		)
		(pad "EP4" smd circle
			(at -8.397494 -2.817368)
			(size 0.381 0.381)
			(layers "F.Cu" "F.Mask" "F.Paste")
			(net "GND")
		)
		(pad "EP13" smd circle
			(at -8.397494 -0.79629)
			(size 0.3048 0.3048)
			(layers "F.Cu" "F.Mask" "F.Paste")
			(net "GND")
		)
		(pad "EP17" smd circle
			(at -8.397494 -0.296164)
			(size 0.3048 0.3048)
			(layers "F.Cu" "F.Mask" "F.Paste")
			(net "P0V9_CPU1_RT3_2A")
		)
		(pad "EP20" smd circle
			(at -8.397494 0.203708)
			(size 0.3048 0.3048)
			(layers "F.Cu" "F.Mask" "F.Paste")
			(net "P0V9_CPU1_RT3_2A")
		)
		(pad "EP22" smd circle
			(at -8.397494 0.703834)
			(size 0.3048 0.3048)
			(layers "F.Cu" "F.Mask" "F.Paste")
			(net "GND")
		)
		(pad "EP32" smd circle
			(at -8.397494 2.724912)
			(size 0.381 0.381)
			(layers "F.Cu" "F.Mask" "F.Paste")
			(net "GND")
		)
		(pad "ER2" smd circle
			(at -8.450072 -3.41884)
			(size 0.3048 0.3048)
			(layers "F.Cu" "F.Mask" "F.Paste")
			(net "GND")
		)
		(pad "ER34" smd circle
			(at -8.450072 3.420364)
			(size 0.3048 0.3048)
			(layers "F.Cu" "F.Mask" "F.Paste")
			(net "GND")
		)
		(pad "ET1" smd oval
			(at -8.750046 -3.938524)
			(size 0.254 0.3302)
			(layers "F.Cu" "F.Mask" "F.Paste")
			(net "GND")
		)
		(pad "ET35" smd oval
			(at -8.750046 3.940048)
			(size 0.254 0.3302)
			(layers "F.Cu" "F.Mask" "F.Paste")
			(net "GND")
		)
		(pad "EU7" smd circle
			(at -8.79729 -2.12471)
			(size 0.381 0.381)
			(layers "F.Cu" "F.Mask" "F.Paste")
			(net "P5E_CPU1_P3_TX_BUF_DP<0>")
		)
		(pad "EU26" smd circle
			(at -8.79729 1.339342)
			(size 0.381 0.381)
			(layers "F.Cu" "F.Mask" "F.Paste")
			(net "P5E_CPU1_P3_RX_DP<0>")
		)
		(pad "EV2" smd circle
			(at -9.05002 -3.41884)
			(size 0.3048 0.3048)
			(layers "F.Cu" "F.Mask" "F.Paste")
			(net "P5E_CPU1_P3_RX_BUF_DN<0>")
		)
		(pad "EV34" smd circle
			(at -9.05002 3.420364)
			(size 0.3048 0.3048)
			(layers "F.Cu" "F.Mask" "F.Paste")
			(net "P5E_CPU1_P3_TX_C_DN<0>")
		)
		(pad "EW10" smd circle
			(at -9.19734 -1.431798)
			(size 0.381 0.381)
			(layers "F.Cu" "F.Mask" "F.Paste")
			(net "P5E_CPU1_P3_TX_BUF_DN<0>")
		)
		(pad "EW29" smd circle
			(at -9.19734 2.032254)
			(size 0.381 0.381)
			(layers "F.Cu" "F.Mask" "F.Paste")
			(net "P5E_CPU1_P3_RX_DN<0>")
		)
		(pad "EY1" smd oval
			(at -9.349994 -3.938524)
			(size 0.254 0.3302)
			(layers "F.Cu" "F.Mask" "F.Paste")
			(net "P5E_CPU1_P3_RX_BUF_DP<0>")
		)
		(pad "EY35" smd oval
			(at -9.349994 3.940048)
			(size 0.254 0.3302)
			(layers "F.Cu" "F.Mask" "F.Paste")
			(net "P5E_CPU1_P3_TX_C_DP<0>")
		)
		(pad "F2" smd circle
			(at 10.150094 -3.41884)
			(size 0.3048 0.3048)
			(layers "F.Cu" "F.Mask" "F.Paste")
			(net "RST_RT_CPU1_P3_PERST_N")
		)
		(pad "F34" smd circle
			(at 10.150094 3.420364)
			(size 0.3048 0.3048)
			(layers "F.Cu" "F.Mask" "F.Paste")
			(net "RT_CPU1_P3_ADDR1")
		)
		(pad "FA15" smd circle
			(at -9.59739 -0.738886)
			(size 0.381 0.381)
			(layers "F.Cu" "F.Mask" "F.Paste")
			(net "GND")
		)
		(pad "FA32" smd circle
			(at -9.59739 2.724912)
			(size 0.381 0.381)
			(layers "F.Cu" "F.Mask" "F.Paste")
			(net "GND")
		)
		(pad "FB2" smd circle
			(at -9.649968 -3.41884)
			(size 0.3048 0.3048)
			(layers "F.Cu" "F.Mask" "F.Paste")
			(net "GND")
		)
		(pad "FB34" smd circle
			(at -9.649968 3.420364)
			(size 0.3048 0.3048)
			(layers "F.Cu" "F.Mask" "F.Paste")
			(net "GND")
		)
		(pad "FC3" smd circle
			(at -9.846818 -2.888488)
			(size 0.3048 0.3048)
			(layers "F.Cu" "F.Mask" "F.Paste")
			(net "GND")
		)
		(pad "FC6" smd circle
			(at -9.846818 -2.288286)
			(size 0.3048 0.3048)
			(layers "F.Cu" "F.Mask" "F.Paste")
			(net "GND")
		)
		(pad "FC9" smd circle
			(at -9.846818 -1.688338)
			(size 0.3048 0.3048)
			(layers "F.Cu" "F.Mask" "F.Paste")
			(net "GND")
		)
		(pad "FC19" smd circle
			(at -9.846818 0.111506)
			(size 0.3048 0.3048)
			(layers "F.Cu" "F.Mask" "F.Paste")
			(net "GND")
		)
		(pad "FC23" smd circle
			(at -9.846818 0.711708)
			(size 0.3048 0.3048)
			(layers "F.Cu" "F.Mask" "F.Paste")
			(net "GND")
		)
		(pad "FC25" smd circle
			(at -9.846818 1.311656)
			(size 0.3048 0.3048)
			(layers "F.Cu" "F.Mask" "F.Paste")
			(net "GND")
		)
		(pad "FC28" smd circle
			(at -9.846818 1.911604)
			(size 0.3048 0.3048)
			(layers "F.Cu" "F.Mask" "F.Paste")
			(net "GND")
		)
		(pad "FD1" smd oval
			(at -9.949942 -3.938524)
			(size 0.254 0.3302)
			(layers "F.Cu" "F.Mask" "F.Paste")
			(net "GND")
		)
		(pad "FD35" smd oval
			(at -9.949942 3.940048)
			(size 0.254 0.3302)
			(layers "F.Cu" "F.Mask" "F.Paste")
			(net "GND")
		)
		(pad "FE2" smd circle
			(at -10.249916 -3.41884)
			(size 0.3048 0.3048)
			(layers "F.Cu" "F.Mask" "F.Paste")
			(net "NCF_CPU1_P3_GND")
		)
		(pad "FE34" smd circle
			(at -10.249916 3.420364)
			(size 0.3048 0.3048)
			(layers "F.Cu" "F.Mask" "F.Paste")
			(net "NCF_CPU1_P3_GND")
		)
		(pad "FF5" smd circle
			(at -10.366248 -2.588514)
			(size 0.3048 0.3048)
			(layers "F.Cu" "F.Mask" "F.Paste")
			(net "SMB_RT_CPU1_P3_ROM_MUX_1D_R_SCL")
		)
		(pad "FF8" smd circle
			(at -10.366248 -1.988312)
			(size 0.3048 0.3048)
			(layers "F.Cu" "F.Mask" "F.Paste")
			(net "JTAG_TEST_MODE_RT_CPU1_P3")
		)
		(pad "FF11" smd circle
			(at -10.366248 -1.388364)
			(size 0.3048 0.3048)
			(layers "F.Cu" "F.Mask" "F.Paste")
			(net "RST_RT_CPU1_P3_RESET_N")
		)
		(pad "FF14" smd circle
			(at -10.366248 -0.788416)
			(size 0.3048 0.3048)
			(layers "F.Cu" "F.Mask" "F.Paste")
			(net "GND")
		)
		(pad "FF18" smd circle
			(at -10.366248 -0.188468)
			(size 0.3048 0.3048)
			(layers "F.Cu" "F.Mask" "F.Paste")
			(net "CLK_100M_RETIMER_CPU1_P3_DN")
		)
		(pad "FF21" smd circle
			(at -10.366248 0.41148)
			(size 0.3048 0.3048)
			(layers "F.Cu" "F.Mask" "F.Paste")
			(net "GND")
		)
		(pad "FF24" smd circle
			(at -10.366248 1.011682)
			(size 0.3048 0.3048)
			(layers "F.Cu" "F.Mask" "F.Paste")
			(net "TEST0_RT_CPU1_P3")
		)
		(pad "FF27" smd circle
			(at -10.366248 1.61163)
			(size 0.3048 0.3048)
			(layers "F.Cu" "F.Mask" "F.Paste")
			(net "TEST1_RT_CPU1_P3")
		)
		(pad "FF30" smd circle
			(at -10.366248 2.211578)
			(size 0.3048 0.3048)
			(layers "F.Cu" "F.Mask" "F.Paste")
			(net "TEST2_RT_CPU1_P3")
		)
		(pad "FF33" smd circle
			(at -10.366248 2.811526)
			(size 0.3048 0.3048)
			(layers "F.Cu" "F.Mask" "F.Paste")
			(net "RT_CPU1_P3_SCAN_MODE")
		)
		(pad "FG1" smd oval
			(at -10.54989 -3.938524)
			(size 0.254 0.3302)
			(layers "F.Cu" "F.Mask" "F.Paste")
			(net "NCF_CPU1_P3_GND")
		)
		(pad "FG35" smd oval
			(at -10.54989 3.940048)
			(size 0.254 0.3302)
			(layers "F.Cu" "F.Mask" "F.Paste")
			(net "NCF_CPU1_P3_GND")
		)
		(pad "FH2" smd circle
			(at -10.850118 -3.41884)
			(size 0.3048 0.3048)
			(layers "F.Cu" "F.Mask" "F.Paste")
			(net "NCF_CPU1_P3_GND")
		)
		(pad "FH34" smd circle
			(at -10.850118 3.420364)
			(size 0.3048 0.3048)
			(layers "F.Cu" "F.Mask" "F.Paste")
			(net "NCF_CPU1_P3_GND")
		)
		(pad "FJ3" smd oval
			(at -10.885932 -2.888488 90)
			(size 0.254 0.3302)
			(layers "F.Cu" "F.Mask" "F.Paste")
			(net "SMB_RT_CPU1_P3_ROM_MUX_1D_R_SDA")
		)
		(pad "FJ6" smd oval
			(at -10.885932 -2.288286 90)
			(size 0.254 0.3302)
			(layers "F.Cu" "F.Mask" "F.Paste")
			(net "Net_2226")
		)
		(pad "FJ9" smd oval
			(at -10.885932 -1.688338 90)
			(size 0.254 0.3302)
			(layers "F.Cu" "F.Mask" "F.Paste")
			(net "MODE_RT_CPU1_P3")
		)
		(pad "FJ12" smd oval
			(at -10.885932 -1.08839 90)
			(size 0.254 0.3302)
			(layers "F.Cu" "F.Mask" "F.Paste")
			(net "GND")
		)
		(pad "FJ16" smd oval
			(at -10.885932 -0.488442 90)
			(size 0.254 0.3302)
			(layers "F.Cu" "F.Mask" "F.Paste")
			(net "CLK_100M_RETIMER_CPU1_P3_DP")
		)
		(pad "FJ19" smd oval
			(at -10.885932 0.111506 90)
			(size 0.254 0.3302)
			(layers "F.Cu" "F.Mask" "F.Paste")
			(net "GND")
		)
		(pad "FJ23" smd oval
			(at -10.885932 0.711708 90)
			(size 0.254 0.3302)
			(layers "F.Cu" "F.Mask" "F.Paste")
			(net "Net_2227")
		)
		(pad "FJ25" smd oval
			(at -10.885932 1.311656 90)
			(size 0.254 0.3302)
			(layers "F.Cu" "F.Mask" "F.Paste")
			(net "GPIO2_RT_CPU1_P3")
		)
		(pad "FJ28" smd oval
			(at -10.885932 1.911604 90)
			(size 0.254 0.3302)
			(layers "F.Cu" "F.Mask" "F.Paste")
			(net "GPIO3_RT_CPU1_P3")
		)
		(pad "FJ31" smd oval
			(at -10.885932 2.511552 90)
			(size 0.254 0.3302)
			(layers "F.Cu" "F.Mask" "F.Paste")
			(net "Net_57")
		)
		(pad "G1" smd oval
			(at 9.85012 -3.938524)
			(size 0.254 0.3302)
			(layers "F.Cu" "F.Mask" "F.Paste")
			(net "RT_CPU1_P3_VQPS")
		)
		(pad "G35" smd oval
			(at 9.85012 3.940048)
			(size 0.254 0.3302)
			(layers "F.Cu" "F.Mask" "F.Paste")
			(net "CLKREQ_RT_CPU1_P3_N")
		)
		(pad "H12" smd circle
			(at 9.846818 -1.08839)
			(size 0.3048 0.3048)
			(layers "F.Cu" "F.Mask" "F.Paste")
			(net "GND")
		)
		(pad "H16" smd circle
			(at 9.846818 -0.488442)
			(size 0.3048 0.3048)
			(layers "F.Cu" "F.Mask" "F.Paste")
			(net "GND")
		)
		(pad "H19" smd circle
			(at 9.846818 0.111506)
			(size 0.3048 0.3048)
			(layers "F.Cu" "F.Mask" "F.Paste")
			(net "GND")
		)
		(pad "H31" smd circle
			(at 9.846818 2.511552)
			(size 0.3048 0.3048)
			(layers "F.Cu" "F.Mask" "F.Paste")
			(net "GND")
		)
		(pad "J4" smd circle
			(at 9.602724 -2.817368)
			(size 0.381 0.381)
			(layers "F.Cu" "F.Mask" "F.Paste")
			(net "GND")
		)
		(pad "J22" smd circle
			(at 9.602724 0.703834)
			(size 0.3048 0.3048)
			(layers "F.Cu" "F.Mask" "F.Paste")
			(net "GND")
		)
		(pad "K2" smd circle
			(at 9.549892 -3.41884)
			(size 0.3048 0.3048)
			(layers "F.Cu" "F.Mask" "F.Paste")
			(net "GND")
		)
		(pad "K34" smd circle
			(at 9.549892 3.420364)
			(size 0.3048 0.3048)
			(layers "F.Cu" "F.Mask" "F.Paste")
			(net "GND")
		)
		(pad "L1" smd oval
			(at 9.249918 -3.938524)
			(size 0.254 0.3302)
			(layers "F.Cu" "F.Mask" "F.Paste")
			(net "GND")
		)
		(pad "L35" smd oval
			(at 9.249918 3.940048)
			(size 0.254 0.3302)
			(layers "F.Cu" "F.Mask" "F.Paste")
			(net "GND")
		)
		(pad "M7" smd circle
			(at 9.202674 -2.12471)
			(size 0.381 0.381)
			(layers "F.Cu" "F.Mask" "F.Paste")
			(net "P5E_CPU1_P3_TX_BUF_DP<15>")
		)
		(pad "M26" smd circle
			(at 9.202674 1.339342)
			(size 0.381 0.381)
			(layers "F.Cu" "F.Mask" "F.Paste")
			(net "P5E_CPU1_P3_RX_DP<15>")
		)
		(pad "N2" smd circle
			(at 8.949944 -3.41884)
			(size 0.3048 0.3048)
			(layers "F.Cu" "F.Mask" "F.Paste")
			(net "P5E_CPU1_P3_RX_BUF_DN<15>")
		)
		(pad "N34" smd circle
			(at 8.949944 3.420364)
			(size 0.3048 0.3048)
			(layers "F.Cu" "F.Mask" "F.Paste")
			(net "P5E_CPU1_P3_TX_C_DN<15>")
		)
	)
)
